(kicad_pcb
	(version 20260206)
	(generator "pcbnew")
	(generator_version "10.0")
	(general
		(thickness 1.6)
		(legacy_teardrops no)
	)
	(paper "A4")
	(title_block
		(title "03242023_DA0F0TMBIJ0_F0T_Motherboard_J_brd_V01_OCP.brd")
		(comment 1 "Grand Teton / footprints 1987-1993 of 6105")
	)
	(layers
		(0 "F.Cu" signal "TOP")
		(4 "In1.Cu" signal "GND")
		(6 "In2.Cu" signal "IN1")
		(8 "In3.Cu" signal "GND1")
		(10 "In4.Cu" signal "IN2")
		(12 "In5.Cu" signal "GND2")
		(14 "In6.Cu" signal "IN3")
		(16 "In7.Cu" signal "GND3")
		(18 "In8.Cu" signal "VCC")
		(20 "In9.Cu" signal "VCC1")
		(22 "In10.Cu" signal "GND4")
		(24 "In11.Cu" signal "IN4")
		(26 "In12.Cu" signal "GND5")
		(28 "In13.Cu" signal "IN5")
		(30 "In14.Cu" signal "GND6")
		(32 "In15.Cu" signal "IN6")
		(34 "In16.Cu" signal "GND7")
		(2 "B.Cu" signal "BOTTOM")
		(9 "F.Adhes" user "F.Adhesive")
		(11 "B.Adhes" user "B.Adhesive")
		(13 "F.Paste" user "Package Geometry/Pastemask Top")
		(15 "B.Paste" user "Package Geometry/Pastemask Bottom")
		(5 "F.SilkS" user "Ref Des/Silkscreen Top")
		(7 "B.SilkS" user "Ref Des/Silkscreen Bottom")
		(1 "F.Mask" user "Board Geometry/Soldermask Top")
		(3 "B.Mask" user "Board Geometry/Soldermask Bottom")
		(17 "Dwgs.User" user "User.Drawings")
		(19 "Cmts.User" user "User.Comments")
		(21 "Eco1.User" user "User.Eco1")
		(23 "Eco2.User" user "User.Eco2")
		(25 "Edge.Cuts" user "Board Geometry/Outline")
		(27 "Margin" user)
		(31 "F.CrtYd" user "Package Geometry/Place Bound Top")
		(29 "B.CrtYd" user "Package Geometry/Place Bound Bottom")
		(35 "F.Fab" user "Ref Des/Assembly Top")
		(33 "B.Fab" user "Ref Des/Assembly Bottom")
	)
	(footprint ""
		(layer "F.Cu")
		(at 214.4268 -107.4166 -90)
		(property "Reference" "C2382"
			(at 0 0 270)
			(layer "F.SilkS")
			(hide yes)
			(effects
				(font
					(size 1.27 1.27)
				)
			)
		)
		(property "Value" ""
			(at 0 0 270)
			(layer "F.Fab")
			(effects
				(font
					(size 1.27 1.27)
				)
			)
		)
		(duplicate_pad_numbers_are_jumpers no)
		(fp_line
			(start -0.7874 0.4064)
			(end -0.7874 -0.4064)
			(stroke
				(width 0.1524)
				(type default)
			)
			(layer "F.SilkS")
		)
		(fp_line
			(start 0.7874 0.4064)
			(end -0.7874 0.4064)
			(stroke
				(width 0.1524)
				(type default)
			)
			(layer "F.SilkS")
		)
		(fp_line
			(start -0.7874 -0.4064)
			(end 0.7874 -0.4064)
			(stroke
				(width 0.1524)
				(type default)
			)
			(layer "F.SilkS")
		)
		(fp_line
			(start 0.7874 -0.4064)
			(end 0.7874 0.4064)
			(stroke
				(width 0.1524)
				(type default)
			)
			(layer "F.SilkS")
		)
		(fp_line
			(start -0.67945 0.3048)
			(end -0.67945 -0.305054)
			(stroke
				(width 0.1)
				(type default)
			)
			(layer "F.Fab")
		)
		(fp_line
			(start -0.12065 0.3048)
			(end -0.67945 0.3048)
			(stroke
				(width 0.1)
				(type default)
			)
			(layer "F.Fab")
		)
		(fp_line
			(start 0.120396 0.3048)
			(end 0.120396 0.2794)
			(stroke
				(width 0.1)
				(type default)
			)
			(layer "F.Fab")
		)
		(fp_line
			(start 0.67945 0.3048)
			(end 0.120396 0.3048)
			(stroke
				(width 0.1)
				(type default)
			)
			(layer "F.Fab")
		)
		(fp_line
			(start -0.12065 0.2794)
			(end -0.12065 0.3048)
			(stroke
				(width 0.1)
				(type default)
			)
			(layer "F.Fab")
		)
		(fp_line
			(start 0.120396 0.2794)
			(end -0.12065 0.2794)
			(stroke
				(width 0.1)
				(type default)
			)
			(layer "F.Fab")
		)
		(fp_line
			(start -0.12065 -0.2794)
			(end 0.12065 -0.2794)
			(stroke
				(width 0.1)
				(type default)
			)
			(layer "F.Fab")
		)
		(fp_line
			(start 0.12065 -0.2794)
			(end 0.12065 -0.3048)
			(stroke
				(width 0.1)
				(type default)
			)
			(layer "F.Fab")
		)
		(fp_line
			(start 0.12065 -0.3048)
			(end 0.67945 -0.3048)
			(stroke
				(width 0.1)
				(type default)
			)
			(layer "F.Fab")
		)
		(fp_line
			(start 0.67945 -0.3048)
			(end 0.67945 0.3048)
			(stroke
				(width 0.1)
				(type default)
			)
			(layer "F.Fab")
		)
		(fp_line
			(start -0.67945 -0.305054)
			(end -0.12065 -0.305054)
			(stroke
				(width 0.1)
				(type default)
			)
			(layer "F.Fab")
		)
		(fp_line
			(start -0.12065 -0.305054)
			(end -0.12065 -0.2794)
			(stroke
				(width 0.1)
				(type default)
			)
			(layer "F.Fab")
		)
		(pad "1" smd circle
			(at -0.40005 0 270)
			(size 0 0)
			(layers "F.Cu" "F.Mask" "F.Paste")
			(net "P12V_AUX_UV_TRIGGER")
		)
		(pad "2" smd circle
			(at 0.40005 0 270)
			(size 0 0)
			(layers "F.Cu" "F.Mask" "F.Paste")
			(net "GND")
		)
	)
	(footprint ""
		(layer "F.Cu")
		(at 411.21965 -402.371052 -90)
		(property "Reference" "C961"
			(at 0 0 270)
			(layer "F.SilkS")
			(hide yes)
			(effects
				(font
					(size 1.27 1.27)
				)
			)
		)
		(property "Value" ""
			(at 0 0 270)
			(layer "F.Fab")
			(effects
				(font
					(size 1.27 1.27)
				)
			)
		)
		(duplicate_pad_numbers_are_jumpers no)
		(fp_line
			(start -0.299974 0.150114)
			(end -0.299974 -0.150114)
			(stroke
				(width 0.1)
				(type default)
			)
			(layer "F.Fab")
		)
		(fp_line
			(start 0.299974 0.150114)
			(end -0.299974 0.150114)
			(stroke
				(width 0.1)
				(type default)
			)
			(layer "F.Fab")
		)
		(fp_line
			(start -0.299974 -0.150114)
			(end 0.299974 -0.150114)
			(stroke
				(width 0.1)
				(type default)
			)
			(layer "F.Fab")
		)
		(fp_line
			(start 0.299974 -0.150114)
			(end 0.299974 0.150114)
			(stroke
				(width 0.1)
				(type default)
			)
			(layer "F.Fab")
		)
		(pad "1" smd rect
			(at -0.2667 0 270)
			(size 0.3048 0.381)
			(layers "F.Cu" "F.Mask" "F.Paste")
			(net "P5E_CPU0_PE2_TX_C_DP<2>")
		)
		(pad "2" smd rect
			(at 0.2667 0 270)
			(size 0.3048 0.381)
			(layers "F.Cu" "F.Mask" "F.Paste")
			(net "P5E_CPU0_PE2_TX_DP<2>")
		)
	)
	(footprint ""
		(layer "F.Cu")
		(at 176.17948 -425.414948)
		(property "Reference" "R2917"
			(at 0 0 0)
			(layer "F.SilkS")
			(hide yes)
			(effects
				(font
					(size 1.27 1.27)
				)
			)
		)
		(property "Value" ""
			(at 0 0 0)
			(layer "F.Fab")
			(effects
				(font
					(size 1.27 1.27)
				)
			)
		)
		(duplicate_pad_numbers_are_jumpers no)
		(fp_line
			(start -0.7874 -0.4064)
			(end 0.7874 -0.4064)
			(stroke
				(width 0.1524)
				(type default)
			)
			(layer "F.SilkS")
		)
		(fp_line
			(start -0.7874 0.4064)
			(end -0.7874 -0.4064)
			(stroke
				(width 0.1524)
				(type default)
			)
			(layer "F.SilkS")
		)
		(fp_line
			(start 0.7874 -0.4064)
			(end 0.7874 0.4064)
			(stroke
				(width 0.1524)
				(type default)
			)
			(layer "F.SilkS")
		)
		(fp_line
			(start 0.7874 0.4064)
			(end -0.7874 0.4064)
			(stroke
				(width 0.1524)
				(type default)
			)
			(layer "F.SilkS")
		)
		(fp_line
			(start -0.67945 -0.305054)
			(end -0.12065 -0.305054)
			(stroke
				(width 0.1)
				(type default)
			)
			(layer "F.Fab")
		)
		(fp_line
			(start -0.67945 0.3048)
			(end -0.67945 -0.305054)
			(stroke
				(width 0.1)
				(type default)
			)
			(layer "F.Fab")
		)
		(fp_line
			(start -0.12065 -0.305054)
			(end -0.12065 -0.2794)
			(stroke
				(width 0.1)
				(type default)
			)
			(layer "F.Fab")
		)
		(fp_line
			(start -0.12065 -0.2794)
			(end 0.12065 -0.2794)
			(stroke
				(width 0.1)
				(type default)
			)
			(layer "F.Fab")
		)
		(fp_line
			(start -0.12065 0.2794)
			(end -0.12065 0.3048)
			(stroke
				(width 0.1)
				(type default)
			)
			(layer "F.Fab")
		)
		(fp_line
			(start -0.12065 0.3048)
			(end -0.67945 0.3048)
			(stroke
				(width 0.1)
				(type default)
			)
			(layer "F.Fab")
		)
		(fp_line
			(start 0.120396 0.2794)
			(end -0.12065 0.2794)
			(stroke
				(width 0.1)
				(type default)
			)
			(layer "F.Fab")
		)
		(fp_line
			(start 0.120396 0.3048)
			(end 0.120396 0.2794)
			(stroke
				(width 0.1)
				(type default)
			)
			(layer "F.Fab")
		)
		(fp_line
			(start 0.12065 -0.3048)
			(end 0.67945 -0.3048)
			(stroke
				(width 0.1)
				(type default)
			)
			(layer "F.Fab")
		)
		(fp_line
			(start 0.12065 -0.2794)
			(end 0.12065 -0.3048)
			(stroke
				(width 0.1)
				(type default)
			)
			(layer "F.Fab")
		)
		(fp_line
			(start 0.67945 -0.3048)
			(end 0.67945 0.3048)
			(stroke
				(width 0.1)
				(type default)
			)
			(layer "F.Fab")
		)
		(fp_line
			(start 0.67945 0.3048)
			(end 0.120396 0.3048)
			(stroke
				(width 0.1)
				(type default)
			)
			(layer "F.Fab")
		)
		(pad "1" smd circle
			(at -0.40005 0)
			(size 0 0)
			(layers "F.Cu" "F.Mask" "F.Paste")
			(net "BMC_MONITER_BUF_R")
		)
		(pad "2" smd circle
			(at 0.40005 0)
			(size 0 0)
			(layers "F.Cu" "F.Mask" "F.Paste")
			(net "BMC_MONITER_BUF")
		)
	)
	(footprint ""
		(layer "F.Cu")
		(at 319.270888 -402.371052 -90)
		(property "Reference" "C1568"
			(at 0 0 270)
			(layer "F.SilkS")
			(hide yes)
			(effects
				(font
					(size 1.27 1.27)
				)
			)
		)
		(property "Value" ""
			(at 0 0 270)
			(layer "F.Fab")
			(effects
				(font
					(size 1.27 1.27)
				)
			)
		)
		(duplicate_pad_numbers_are_jumpers no)
		(fp_line
			(start -0.299974 0.150114)
			(end -0.299974 -0.150114)
			(stroke
				(width 0.1)
				(type default)
			)
			(layer "F.Fab")
		)
		(fp_line
			(start 0.299974 0.150114)
			(end -0.299974 0.150114)
			(stroke
				(width 0.1)
				(type default)
			)
			(layer "F.Fab")
		)
		(fp_line
			(start -0.299974 -0.150114)
			(end 0.299974 -0.150114)
			(stroke
				(width 0.1)
				(type default)
			)
			(layer "F.Fab")
		)
		(fp_line
			(start 0.299974 -0.150114)
			(end 0.299974 0.150114)
			(stroke
				(width 0.1)
				(type default)
			)
			(layer "F.Fab")
		)
		(pad "1" smd rect
			(at -0.2667 0 270)
			(size 0.3048 0.381)
			(layers "F.Cu" "F.Mask" "F.Paste")
			(net "P5E_CPU0_PE4_TX_C_DN<5>")
		)
		(pad "2" smd rect
			(at 0.2667 0 270)
			(size 0.3048 0.381)
			(layers "F.Cu" "F.Mask" "F.Paste")
			(net "P5E_CPU0_PE4_TX_DN<5>")
		)
	)
	(footprint ""
		(layer "F.Cu")
		(at 358.76865 -412.0388)
		(property "Reference" "R4800"
			(at 0 0 0)
			(layer "F.SilkS")
			(hide yes)
			(effects
				(font
					(size 1.27 1.27)
				)
			)
		)
		(property "Value" ""
			(at 0 0 0)
			(layer "F.Fab")
			(effects
				(font
					(size 1.27 1.27)
				)
			)
		)
		(duplicate_pad_numbers_are_jumpers no)
		(fp_line
			(start -0.7874 -0.4064)
			(end 0.7874 -0.4064)
			(stroke
				(width 0.1524)
				(type default)
			)
			(layer "F.SilkS")
		)
		(fp_line
			(start -0.7874 0.4064)
			(end -0.7874 -0.4064)
			(stroke
				(width 0.1524)
				(type default)
			)
			(layer "F.SilkS")
		)
		(fp_line
			(start 0.7874 -0.4064)
			(end 0.7874 0.4064)
			(stroke
				(width 0.1524)
				(type default)
			)
			(layer "F.SilkS")
		)
		(fp_line
			(start 0.7874 0.4064)
			(end -0.7874 0.4064)
			(stroke
				(width 0.1524)
				(type default)
			)
			(layer "F.SilkS")
		)
		(fp_line
			(start -0.67945 -0.305054)
			(end -0.12065 -0.305054)
			(stroke
				(width 0.1)
				(type default)
			)
			(layer "F.Fab")
		)
		(fp_line
			(start -0.67945 0.3048)
			(end -0.67945 -0.305054)
			(stroke
				(width 0.1)
				(type default)
			)
			(layer "F.Fab")
		)
		(fp_line
			(start -0.12065 -0.305054)
			(end -0.12065 -0.2794)
			(stroke
				(width 0.1)
				(type default)
			)
			(layer "F.Fab")
		)
		(fp_line
			(start -0.12065 -0.2794)
			(end 0.12065 -0.2794)
			(stroke
				(width 0.1)
				(type default)
			)
			(layer "F.Fab")
		)
		(fp_line
			(start -0.12065 0.2794)
			(end -0.12065 0.3048)
			(stroke
				(width 0.1)
				(type default)
			)
			(layer "F.Fab")
		)
		(fp_line
			(start -0.12065 0.3048)
			(end -0.67945 0.3048)
			(stroke
				(width 0.1)
				(type default)
			)
			(layer "F.Fab")
		)
		(fp_line
			(start 0.120396 0.2794)
			(end -0.12065 0.2794)
			(stroke
				(width 0.1)
				(type default)
			)
			(layer "F.Fab")
		)
		(fp_line
			(start 0.120396 0.3048)
			(end 0.120396 0.2794)
			(stroke
				(width 0.1)
				(type default)
			)
			(layer "F.Fab")
		)
		(fp_line
			(start 0.12065 -0.3048)
			(end 0.67945 -0.3048)
			(stroke
				(width 0.1)
				(type default)
			)
			(layer "F.Fab")
		)
		(fp_line
			(start 0.12065 -0.2794)
			(end 0.12065 -0.3048)
			(stroke
				(width 0.1)
				(type default)
			)
			(layer "F.Fab")
		)
		(fp_line
			(start 0.67945 -0.3048)
			(end 0.67945 0.3048)
			(stroke
				(width 0.1)
				(type default)
			)
			(layer "F.Fab")
		)
		(fp_line
			(start 0.67945 0.3048)
			(end 0.120396 0.3048)
			(stroke
				(width 0.1)
				(type default)
			)
			(layer "F.Fab")
		)
		(pad "1" smd circle
			(at -0.40005 0)
			(size 0 0)
			(layers "F.Cu" "F.Mask" "F.Paste")
			(net "P3V3_AUX")
		)
		(pad "2" smd circle
			(at 0.40005 0)
			(size 0 0)
			(layers "F.Cu" "F.Mask" "F.Paste")
			(net "PRSNT_CABLE_GPU_A3")
		)
	)
	(footprint ""
		(layer "F.Cu")
		(at 117.581934 -108.331762 -90)
		(property "Reference" "C2246"
			(at 0 0 270)
			(layer "F.SilkS")
			(hide yes)
			(effects
				(font
					(size 1.27 1.27)
				)
			)
		)
		(property "Value" ""
			(at 0 0 270)
			(layer "F.Fab")
			(effects
				(font
					(size 1.27 1.27)
				)
			)
		)
		(duplicate_pad_numbers_are_jumpers no)
		(fp_line
			(start -0.7874 0.4064)
			(end -0.7874 -0.4064)
			(stroke
				(width 0.1524)
				(type default)
			)
			(layer "F.SilkS")
		)
		(fp_line
			(start 0.7874 0.4064)
			(end -0.7874 0.4064)
			(stroke
				(width 0.1524)
				(type default)
			)
			(layer "F.SilkS")
		)
		(fp_line
			(start -0.7874 -0.4064)
			(end 0.7874 -0.4064)
			(stroke
				(width 0.1524)
				(type default)
			)
			(layer "F.SilkS")
		)
		(fp_line
			(start 0.7874 -0.4064)
			(end 0.7874 0.4064)
			(stroke
				(width 0.1524)
				(type default)
			)
			(layer "F.SilkS")
		)
		(fp_line
			(start -0.67945 0.3048)
			(end -0.67945 -0.305054)
			(stroke
				(width 0.1)
				(type default)
			)
			(layer "F.Fab")
		)
		(fp_line
			(start -0.12065 0.3048)
			(end -0.67945 0.3048)
			(stroke
				(width 0.1)
				(type default)
			)
			(layer "F.Fab")
		)
		(fp_line
			(start 0.120396 0.3048)
			(end 0.120396 0.2794)
			(stroke
				(width 0.1)
				(type default)
			)
			(layer "F.Fab")
		)
		(fp_line
			(start 0.67945 0.3048)
			(end 0.120396 0.3048)
			(stroke
				(width 0.1)
				(type default)
			)
			(layer "F.Fab")
		)
		(fp_line
			(start -0.12065 0.2794)
			(end -0.12065 0.3048)
			(stroke
				(width 0.1)
				(type default)
			)
			(layer "F.Fab")
		)
		(fp_line
			(start 0.120396 0.2794)
			(end -0.12065 0.2794)
			(stroke
				(width 0.1)
				(type default)
			)
			(layer "F.Fab")
		)
		(fp_line
			(start -0.12065 -0.2794)
			(end 0.12065 -0.2794)
			(stroke
				(width 0.1)
				(type default)
			)
			(layer "F.Fab")
		)
		(fp_line
			(start 0.12065 -0.2794)
			(end 0.12065 -0.3048)
			(stroke
				(width 0.1)
				(type default)
			)
			(layer "F.Fab")
		)
		(fp_line
			(start 0.12065 -0.3048)
			(end 0.67945 -0.3048)
			(stroke
				(width 0.1)
				(type default)
			)
			(layer "F.Fab")
		)
		(fp_line
			(start 0.67945 -0.3048)
			(end 0.67945 0.3048)
			(stroke
				(width 0.1)
				(type default)
			)
			(layer "F.Fab")
		)
		(fp_line
			(start -0.67945 -0.305054)
			(end -0.12065 -0.305054)
			(stroke
				(width 0.1)
				(type default)
			)
			(layer "F.Fab")
		)
		(fp_line
			(start -0.12065 -0.305054)
			(end -0.12065 -0.2794)
			(stroke
				(width 0.1)
				(type default)
			)
			(layer "F.Fab")
		)
		(pad "1" smd circle
			(at -0.40005 0 270)
			(size 0 0)
			(layers "F.Cu" "F.Mask" "F.Paste")
			(net "P3V3_AUX")
		)
		(pad "2" smd circle
			(at 0.40005 0 270)
			(size 0 0)
			(layers "F.Cu" "F.Mask" "F.Paste")
			(net "GND")
		)
	)
	(footprint ""
		(layer "F.Cu")
		(at 310.007 -53.050948 -90)
		(property "Reference" "R315"
			(at 0 0 270)
			(layer "F.SilkS")
			(hide yes)
			(effects
				(font
					(size 1.27 1.27)
				)
			)
		)
		(property "Value" ""
			(at 0 0 270)
			(layer "F.Fab")
			(effects
				(font
					(size 1.27 1.27)
				)
			)
		)
		(duplicate_pad_numbers_are_jumpers no)
		(fp_line
			(start -0.7874 0.4064)
			(end -0.7874 -0.4064)
			(stroke
				(width 0.1524)
				(type default)
			)
			(layer "F.SilkS")
		)
		(fp_line
			(start 0.7874 0.4064)
			(end -0.7874 0.4064)
			(stroke
				(width 0.1524)
				(type default)
			)
			(layer "F.SilkS")
		)
		(fp_line
			(start -0.7874 -0.4064)
			(end 0.7874 -0.4064)
			(stroke
				(width 0.1524)
				(type default)
			)
			(layer "F.SilkS")
		)
		(fp_line
			(start 0.7874 -0.4064)
			(end 0.7874 0.4064)
			(stroke
				(width 0.1524)
				(type default)
			)
			(layer "F.SilkS")
		)
		(fp_line
			(start -0.67945 0.3048)
			(end -0.67945 -0.305054)
			(stroke
				(width 0.1)
				(type default)
			)
			(layer "F.Fab")
		)
		(fp_line
			(start -0.12065 0.3048)
			(end -0.67945 0.3048)
			(stroke
				(width 0.1)
				(type default)
			)
			(layer "F.Fab")
		)
		(fp_line
			(start 0.120396 0.3048)
			(end 0.120396 0.2794)
			(stroke
				(width 0.1)
				(type default)
			)
			(layer "F.Fab")
		)
		(fp_line
			(start 0.67945 0.3048)
			(end 0.120396 0.3048)
			(stroke
				(width 0.1)
				(type default)
			)
			(layer "F.Fab")
		)
		(fp_line
			(start -0.12065 0.2794)
			(end -0.12065 0.3048)
			(stroke
				(width 0.1)
				(type default)
			)
			(layer "F.Fab")
		)
		(fp_line
			(start 0.120396 0.2794)
			(end -0.12065 0.2794)
			(stroke
				(width 0.1)
				(type default)
			)
			(layer "F.Fab")
		)
		(fp_line
			(start -0.12065 -0.2794)
			(end 0.12065 -0.2794)
			(stroke
				(width 0.1)
				(type default)
			)
			(layer "F.Fab")
		)
		(fp_line
			(start 0.12065 -0.2794)
			(end 0.12065 -0.3048)
			(stroke
				(width 0.1)
				(type default)
			)
			(layer "F.Fab")
		)
		(fp_line
			(start 0.12065 -0.3048)
			(end 0.67945 -0.3048)
			(stroke
				(width 0.1)
				(type default)
			)
			(layer "F.Fab")
		)
		(fp_line
			(start 0.67945 -0.3048)
			(end 0.67945 0.3048)
			(stroke
				(width 0.1)
				(type default)
			)
			(layer "F.Fab")
		)
		(fp_line
			(start -0.67945 -0.305054)
			(end -0.12065 -0.305054)
			(stroke
				(width 0.1)
				(type default)
			)
			(layer "F.Fab")
		)
		(fp_line
			(start -0.12065 -0.305054)
			(end -0.12065 -0.2794)
			(stroke
				(width 0.1)
				(type default)
			)
			(layer "F.Fab")
		)
		(pad "1" smd circle
			(at -0.40005 0 270)
			(size 0 0)
			(layers "F.Cu" "F.Mask" "F.Paste")
			(net "PWRGD_CPUPWRGD_GTL")
		)
		(pad "2" smd circle
			(at 0.40005 0 270)
			(size 0 0)
			(layers "F.Cu" "F.Mask" "F.Paste")
			(net "PWRGD_CPUPWRGD_LVC1_R")
		)
	)
)
